(kicad_pcb
	(version 20260206)
	(generator "pcbnew")
	(generator_version "10.0")
	(general
		(thickness 1.6)
		(legacy_teardrops no)
	)
	(paper "A4")
	(title_block
		(title "timecard-production-celestica-r4006 — R4006-B0001-02_R01.brd")
		(comment 1 "Time Appliance Project (Time Card) / footprints 612-617 of 1113")
	)
	(layers
		(0 "F.Cu" signal "TOP")
		(4 "In1.Cu" signal "L02_GND1")
		(6 "In2.Cu" signal "L03_SIG1")
		(8 "In3.Cu" signal "L04_GND2")
		(10 "In4.Cu" signal "L05_VCC1")
		(12 "In5.Cu" signal "L06_VCC2")
		(14 "In6.Cu" signal "L07_GND3")
		(16 "In7.Cu" signal "L08_SIG2")
		(18 "In8.Cu" signal "L09_GND4")
		(2 "B.Cu" signal "BOTTOM")
		(9 "F.Adhes" user "F.Adhesive")
		(11 "B.Adhes" user "B.Adhesive")
		(13 "F.Paste" user "Package Geometry/Pastemask Top")
		(15 "B.Paste" user "Package Geometry/Pastemask Bottom")
		(5 "F.SilkS" user "Ref Des/Silkscreen Top")
		(7 "B.SilkS" user "Ref Des/Silkscreen Bottom")
		(1 "F.Mask" user "Board Geometry/Soldermask Top")
		(3 "B.Mask" user "Board Geometry/Soldermask Bottom")
		(17 "Dwgs.User" user "User.Drawings")
		(19 "Cmts.User" user "User.Comments")
		(21 "Eco1.User" user "User.Eco1")
		(23 "Eco2.User" user "User.Eco2")
		(25 "Edge.Cuts" user "Board Geometry/Outline")
		(27 "Margin" user)
		(31 "F.CrtYd" user "Package Geometry/Place Bound Top")
		(29 "B.CrtYd" user "Package Geometry/Place Bound Bottom")
		(35 "F.Fab" user "Ref Des/Assembly Top")
		(33 "B.Fab" user "Ref Des/Assembly Bottom")
	)
	(footprint ""
		(layer "F.Cu")
		(at 16.129 -21.463)
		(property "Reference" "TP35"
			(at -0.08763 -0.9398 90)
			(unlocked yes)
			(layer "F.SilkS")
			(effects
				(font
					(size 0.7874 0.5842)
					(thickness 0.1524)
				)
				(justify left)
			)
		)
		(property "Value" ""
			(at 0 0 0)
			(layer "F.Fab")
			(effects
				(font
					(size 1.27 1.27)
				)
			)
		)
		(property "Device Type" "TP_PIONT-TP010CT020B030_PTH-TPA"
			(at -1.341882 0.996696 0)
			(unlocked yes)
			(layer "F.Fab")
			(hide yes)
			(effects
				(font
					(size 0.7874 0.5842)
					(thickness 0.000001)
				)
				(justify left)
			)
		)
		(duplicate_pad_numbers_are_jumpers no)
		(fp_poly
			(pts
				(arc
					(start 0.889 0)
					(mid -0.889 0)
					(end 0.889 0)
				)
			)
			(stroke
				(width 0)
				(type default)
			)
			(fill no)
			(layer "B.CrtYd")
		)
		(fp_poly
			(pts
				(arc
					(start 0.889 0)
					(mid -0.889 0)
					(end 0.889 0)
				)
			)
			(stroke
				(width 0)
				(type default)
			)
			(fill no)
			(layer "F.CrtYd")
		)
		(pad "1" thru_hole circle
			(at 0 0)
			(size 0.508 0.508)
			(drill 0.254)
			(layers "*.Cu" "*.Mask")
			(remove_unused_layers no)
			(net "SMA4_SIG_OUT_BF_EN_N")
			(clearance 0.1016)
			(padstack
				(mode front_inner_back)
				(layer "Inner"
					(shape circle)
					(size 0.508 0.508)
					(clearance 0.1016)
				)
				(layer "B.Cu"
					(shape circle)
					(size 0.762 0.762)
					(clearance -0.0254)
				)
			)
		)
	)
	(footprint ""
		(layer "F.Cu")
		(at 79.756 -46.99)
		(property "Reference" "R98"
			(at 0.127 14.13637 0)
			(unlocked yes)
			(layer "F.SilkS")
			(effects
				(font
					(size 0.7874 0.5842)
					(thickness 0.1524)
				)
			)
		)
		(property "Value" "VAL*"
			(at 0.02032 2.13233 0)
			(unlocked yes)
			(layer "F.Fab")
			(hide yes)
			(effects
				(font
					(size 0.7874 0.5842)
					(thickness 0.1524)
				)
			)
		)
		(property "Device Type" "RESISTOR-G155-100R0-J0,0OHM,-"
			(at 0.008382 1.210564 0)
			(unlocked yes)
			(layer "F.Fab")
			(hide yes)
			(effects
				(font
					(size 0.7874 0.5842)
					(thickness 0.1524)
				)
			)
		)
		(property "User Part Number" "PARTNUM*"
			(at 0.02032 4.024884 0)
			(unlocked yes)
			(layer "Cmts.User")
			(hide yes)
			(effects
				(font
					(size 0.7874 0.5842)
					(thickness 0.1524)
				)
			)
		)
		(property "Tolerance" "TOL*"
			(at 0.044704 3.05435 0)
			(unlocked yes)
			(layer "Cmts.User")
			(hide yes)
			(effects
				(font
					(size 0.7874 0.5842)
					(thickness 0.1524)
				)
			)
		)
		(duplicate_pad_numbers_are_jumpers no)
		(fp_line
			(start -1.143 -0.5588)
			(end -1.143 0.5588)
			(stroke
				(width 0.1)
				(type default)
			)
			(layer "F.SilkS")
		)
		(fp_line
			(start -1.143 0.5588)
			(end 1.143 0.5588)
			(stroke
				(width 0.1)
				(type default)
			)
			(layer "F.SilkS")
		)
		(fp_line
			(start 1.143 -0.5588)
			(end -1.143 -0.5588)
			(stroke
				(width 0.1)
				(type default)
			)
			(layer "F.SilkS")
		)
		(fp_line
			(start 1.143 0.5588)
			(end 1.143 -0.5588)
			(stroke
				(width 0.1)
				(type default)
			)
			(layer "F.SilkS")
		)
		(fp_poly
			(pts
				(xy -1.143 0.5588) (xy 1.143 0.5588) (xy 1.143 -0.5588) (xy -1.143 -0.5588)
			)
			(stroke
				(width 0)
				(type default)
			)
			(fill no)
			(layer "F.CrtYd")
		)
		(fp_line
			(start -0.508 -0.3048)
			(end -0.508 0.3048)
			(stroke
				(width 0.1)
				(type default)
			)
			(layer "F.Fab")
		)
		(fp_line
			(start -0.508 0.3048)
			(end 0.508 0.3048)
			(stroke
				(width 0.1)
				(type default)
			)
			(layer "F.Fab")
		)
		(fp_line
			(start 0.508 -0.3048)
			(end -0.508 -0.3048)
			(stroke
				(width 0.1)
				(type default)
			)
			(layer "F.Fab")
		)
		(fp_line
			(start 0.508 0.3048)
			(end 0.508 -0.3048)
			(stroke
				(width 0.1)
				(type default)
			)
			(layer "F.Fab")
		)
		(pad "1" smd rect
			(at -0.5334 0)
			(size 0.7112 0.6096)
			(layers "F.Cu" "F.Mask" "F.Paste")
			(net "R_MAC_USB_DM")
		)
		(pad "2" smd rect
			(at 0.5334 0)
			(size 0.7112 0.6096)
			(layers "F.Cu" "F.Mask" "F.Paste")
			(net "MUX_USB_DM")
		)
		(zone
			(layer "F.Cu")
			(hatch none 0.5)
			(connect_pads
				(clearance 0)
			)
			(min_thickness 0.25)
			(keepout
				(tracks not_allowed)
				(vias allowed)
				(pads allowed)
				(copperpour not_allowed)
				(footprints allowed)
			)
			(placement
				(enabled no)
				(sheetname "")
			)
			(fill
				(thermal_gap 0.5)
				(thermal_bridge_width 0.5)
				(island_removal_mode 0)
			)
			(polygon
				(pts
					(xy 79.6798 -46.6852) (xy 79.8322 -46.6852) (xy 79.8322 -47.2948) (xy 79.6798 -47.2948)
				)
			)
		)
		(zone
			(layer "F.Cu")
			(hatch none 0.5)
			(connect_pads
				(clearance 0)
			)
			(min_thickness 0.25)
			(keepout
				(tracks allowed)
				(vias not_allowed)
				(pads allowed)
				(copperpour not_allowed)
				(footprints allowed)
			)
			(placement
				(enabled no)
				(sheetname "")
			)
			(fill
				(thermal_gap 0.5)
				(thermal_bridge_width 0.5)
				(island_removal_mode 0)
			)
			(polygon
				(pts
					(xy 79.6798 -46.6852) (xy 79.8322 -46.6852) (xy 79.8322 -47.2948) (xy 79.6798 -47.2948)
				)
			)
		)
	)
	(footprint ""
		(layer "F.Cu")
		(at 133.223 -37.338)
		(property "Reference" "C177"
			(at 4.445 3.97637 0)
			(unlocked yes)
			(layer "F.SilkS")
			(effects
				(font
					(size 0.7874 0.5842)
					(thickness 0.1524)
				)
			)
		)
		(property "Value" "VAL*"
			(at 0.1016 3.769106 0)
			(unlocked yes)
			(layer "F.Fab")
			(hide yes)
			(effects
				(font
					(size 0.7874 0.5842)
					(thickness 0.1524)
				)
			)
		)
		(property "Tolerance" "TOL*"
			(at 0.127 4.734306 0)
			(unlocked yes)
			(layer "Cmts.User")
			(hide yes)
			(effects
				(font
					(size 0.7874 0.5842)
					(thickness 0.1524)
				)
			)
		)
		(property "User Part Number" "PARTNUM*"
			(at 0.2032 5.801106 0)
			(unlocked yes)
			(layer "Cmts.User")
			(hide yes)
			(effects
				(font
					(size 0.7874 0.5842)
					(thickness 0.1524)
				)
			)
		)
		(property "Device Type" "CAPACITOR-G109-0G107-BM,100UF,A"
			(at 0.0762 2.829306 0)
			(unlocked yes)
			(layer "F.Fab")
			(hide yes)
			(effects
				(font
					(size 0.7874 0.5842)
					(thickness 0.1524)
				)
			)
		)
		(duplicate_pad_numbers_are_jumpers no)
		(fp_line
			(start -2.159 -1.5748)
			(end 2.159 -1.5748)
			(stroke
				(width 0.1)
				(type default)
			)
			(layer "F.SilkS")
		)
		(fp_line
			(start -2.159 1.5748)
			(end -2.159 -1.5748)
			(stroke
				(width 0.1)
				(type default)
			)
			(layer "F.SilkS")
		)
		(fp_line
			(start 2.159 -1.5748)
			(end 2.159 1.5748)
			(stroke
				(width 0.1)
				(type default)
			)
			(layer "F.SilkS")
		)
		(fp_line
			(start 2.159 1.5748)
			(end -2.159 1.5748)
			(stroke
				(width 0.1)
				(type default)
			)
			(layer "F.SilkS")
		)
		(fp_rect
			(start -2.159 -1.5748)
			(end 2.159 1.5748)
			(stroke
				(width 0)
				(type default)
			)
			(fill no)
			(layer "F.CrtYd")
		)
		(fp_line
			(start -1.6002 -1.2446)
			(end -1.6002 1.2446)
			(stroke
				(width 0.1)
				(type default)
			)
			(layer "F.Fab")
		)
		(fp_line
			(start -1.6002 1.2446)
			(end 1.6002 1.2446)
			(stroke
				(width 0.1)
				(type default)
			)
			(layer "F.Fab")
		)
		(fp_line
			(start 1.6002 -1.2446)
			(end -1.6002 -1.2446)
			(stroke
				(width 0.1)
				(type default)
			)
			(layer "F.Fab")
		)
		(fp_line
			(start 1.6002 1.2446)
			(end 1.6002 -1.2446)
			(stroke
				(width 0.1)
				(type default)
			)
			(layer "F.Fab")
		)
		(pad "1" smd rect
			(at -1.3335 0)
			(size 1.143 2.6416)
			(layers "F.Cu" "F.Mask" "F.Paste")
			(net "XP1R0V_FPGA_VCCINT")
		)
		(pad "2" smd rect
			(at 1.3335 0)
			(size 1.143 2.6416)
			(layers "F.Cu" "F.Mask" "F.Paste")
			(net "SG")
		)
		(zone
			(layer "F.Cu")
			(hatch none 0.5)
			(connect_pads
				(clearance 0)
			)
			(min_thickness 0.25)
			(keepout
				(tracks allowed)
				(vias not_allowed)
				(pads allowed)
				(copperpour not_allowed)
				(footprints allowed)
			)
			(placement
				(enabled no)
				(sheetname "")
			)
			(fill
				(thermal_gap 0.5)
				(thermal_bridge_width 0.5)
				(island_removal_mode 0)
			)
			(polygon
				(pts
					(xy 132.5372 -38.735) (xy 132.5372 -35.941) (xy 133.9088 -35.941) (xy 133.9088 -38.735)
				)
			)
		)
	)
	(footprint ""
		(layer "F.Cu")
		(at 35.179 -104.267 -90)
		(property "Reference" "R6"
			(at -1.397 4.02463 90)
			(unlocked yes)
			(layer "F.SilkS")
			(effects
				(font
					(size 0.7874 0.5842)
					(thickness 0.1524)
				)
			)
		)
		(property "Value" "VAL*"
			(at 0.02032 2.13233 270)
			(unlocked yes)
			(layer "F.Fab")
			(hide yes)
			(effects
				(font
					(size 0.7874 0.5842)
					(thickness 0.1524)
				)
			)
		)
		(property "Device Type" "RESISTOR-G155-120R0-01,20OHM,1%"
			(at 0.008382 1.210564 270)
			(unlocked yes)
			(layer "F.Fab")
			(hide yes)
			(effects
				(font
					(size 0.7874 0.5842)
					(thickness 0.1524)
				)
			)
		)
		(property "User Part Number" "PARTNUM*"
			(at 0.02032 4.024884 270)
			(unlocked yes)
			(layer "Cmts.User")
			(hide yes)
			(effects
				(font
					(size 0.7874 0.5842)
					(thickness 0.1524)
				)
			)
		)
		(property "Tolerance" "TOL*"
			(at 0.044704 3.05435 270)
			(unlocked yes)
			(layer "Cmts.User")
			(hide yes)
			(effects
				(font
					(size 0.7874 0.5842)
					(thickness 0.1524)
				)
			)
		)
		(duplicate_pad_numbers_are_jumpers no)
		(fp_line
			(start -1.143 0.5588)
			(end 1.143 0.5588)
			(stroke
				(width 0.1)
				(type default)
			)
			(layer "F.SilkS")
		)
		(fp_line
			(start 1.143 0.5588)
			(end 1.143 -0.5588)
			(stroke
				(width 0.1)
				(type default)
			)
			(layer "F.SilkS")
		)
		(fp_line
			(start -1.143 -0.5588)
			(end -1.143 0.5588)
			(stroke
				(width 0.1)
				(type default)
			)
			(layer "F.SilkS")
		)
		(fp_line
			(start 1.143 -0.5588)
			(end -1.143 -0.5588)
			(stroke
				(width 0.1)
				(type default)
			)
			(layer "F.SilkS")
		)
		(fp_rect
			(start -1.143 -0.5588)
			(end 1.143 0.5588)
			(stroke
				(width 0)
				(type default)
			)
			(fill no)
			(layer "F.CrtYd")
		)
		(fp_line
			(start -0.508 0.3048)
			(end 0.508 0.3048)
			(stroke
				(width 0.1)
				(type default)
			)
			(layer "F.Fab")
		)
		(fp_line
			(start 0.508 0.3048)
			(end 0.508 -0.3048)
			(stroke
				(width 0.1)
				(type default)
			)
			(layer "F.Fab")
		)
		(fp_line
			(start -0.508 -0.3048)
			(end -0.508 0.3048)
			(stroke
				(width 0.1)
				(type default)
			)
			(layer "F.Fab")
		)
		(fp_line
			(start 0.508 -0.3048)
			(end -0.508 -0.3048)
			(stroke
				(width 0.1)
				(type default)
			)
			(layer "F.Fab")
		)
		(pad "1" smd rect
			(at -0.5334 0 270)
			(size 0.7112 0.6096)
			(layers "F.Cu" "F.Mask" "F.Paste")
			(net "XP5R0V")
		)
		(pad "2" smd rect
			(at 0.5334 0 270)
			(size 0.7112 0.6096)
			(layers "F.Cu" "F.Mask" "F.Paste")
			(net "UNNAMED_516_CAPACITOR_I29_1")
		)
		(zone
			(layer "F.Cu")
			(hatch none 0.5)
			(connect_pads
				(clearance 0)
			)
			(min_thickness 0.25)
			(keepout
				(tracks allowed)
				(vias not_allowed)
				(pads allowed)
				(copperpour not_allowed)
				(footprints allowed)
			)
			(placement
				(enabled no)
				(sheetname "")
			)
			(fill
				(thermal_gap 0.5)
				(thermal_bridge_width 0.5)
				(island_removal_mode 0)
			)
			(polygon
				(pts
					(xy 35.4838 -104.3432) (xy 34.8742 -104.3432) (xy 34.8742 -104.1908) (xy 35.4838 -104.1908)
				)
			)
		)
	)
	(footprint ""
		(layer "F.Cu")
		(at 84.709 -64.3128 -90)
		(property "Reference" "R304"
			(at -13.4112 9.99363 90)
			(unlocked yes)
			(layer "F.SilkS")
			(effects
				(font
					(size 0.7874 0.5842)
					(thickness 0.1524)
				)
			)
		)
		(property "Value" "VAL*"
			(at 0.02032 2.13233 270)
			(unlocked yes)
			(layer "F.Fab")
			(hide yes)
			(effects
				(font
					(size 0.7874 0.5842)
					(thickness 0.1524)
				)
			)
		)
		(property "Device Type" "RESISTOR-G155-14701-01,4.7KOHMA"
			(at 0.008382 1.210564 270)
			(unlocked yes)
			(layer "F.Fab")
			(hide yes)
			(effects
				(font
					(size 0.7874 0.5842)
					(thickness 0.1524)
				)
			)
		)
		(property "User Part Number" "PARTNUM*"
			(at 0.02032 4.024884 270)
			(unlocked yes)
			(layer "Cmts.User")
			(hide yes)
			(effects
				(font
					(size 0.7874 0.5842)
					(thickness 0.1524)
				)
			)
		)
		(property "Tolerance" "TOL*"
			(at 0.044704 3.05435 270)
			(unlocked yes)
			(layer "Cmts.User")
			(hide yes)
			(effects
				(font
					(size 0.7874 0.5842)
					(thickness 0.1524)
				)
			)
		)
		(duplicate_pad_numbers_are_jumpers no)
		(fp_line
			(start -1.143 0.5588)
			(end 1.143 0.5588)
			(stroke
				(width 0.1)
				(type default)
			)
			(layer "F.SilkS")
		)
		(fp_line
			(start 1.143 0.5588)
			(end 1.143 -0.5588)
			(stroke
				(width 0.1)
				(type default)
			)
			(layer "F.SilkS")
		)
		(fp_line
			(start -1.143 -0.5588)
			(end -1.143 0.5588)
			(stroke
				(width 0.1)
				(type default)
			)
			(layer "F.SilkS")
		)
		(fp_line
			(start 1.143 -0.5588)
			(end -1.143 -0.5588)
			(stroke
				(width 0.1)
				(type default)
			)
			(layer "F.SilkS")
		)
		(fp_rect
			(start 1.143 0.5588)
			(end -1.143 -0.5588)
			(stroke
				(width 0)
				(type default)
			)
			(fill no)
			(layer "F.CrtYd")
		)
		(fp_line
			(start -0.508 0.3048)
			(end 0.508 0.3048)
			(stroke
				(width 0.1)
				(type default)
			)
			(layer "F.Fab")
		)
		(fp_line
			(start 0.508 0.3048)
			(end 0.508 -0.3048)
			(stroke
				(width 0.1)
				(type default)
			)
			(layer "F.Fab")
		)
		(fp_line
			(start -0.508 -0.3048)
			(end -0.508 0.3048)
			(stroke
				(width 0.1)
				(type default)
			)
			(layer "F.Fab")
		)
		(fp_line
			(start 0.508 -0.3048)
			(end -0.508 -0.3048)
			(stroke
				(width 0.1)
				(type default)
			)
			(layer "F.Fab")
		)
		(pad "1" smd rect
			(at -0.5334 0 270)
			(size 0.7112 0.6096)
			(layers "F.Cu" "F.Mask" "F.Paste")
			(net "XP3R3V_FPGA")
		)
		(pad "2" smd rect
			(at 0.5334 0 270)
			(size 0.7112 0.6096)
			(layers "F.Cu" "F.Mask" "F.Paste")
			(net "R_BNO080_BOOT_N")
		)
		(zone
			(layer "F.Cu")
			(hatch none 0.5)
			(connect_pads
				(clearance 0)
			)
			(min_thickness 0.25)
			(keepout
				(tracks allowed)
				(vias not_allowed)
				(pads allowed)
				(copperpour not_allowed)
				(footprints allowed)
			)
			(placement
				(enabled no)
				(sheetname "")
			)
			(fill
				(thermal_gap 0.5)
				(thermal_bridge_width 0.5)
				(island_removal_mode 0)
			)
			(polygon
				(pts
					(xy 84.4042 -64.2366) (xy 85.0138 -64.2366) (xy 85.0138 -64.389) (xy 84.4042 -64.389)
				)
			)
		)
	)
	(footprint ""
		(layer "F.Cu")
		(at 112.776 -61.976 90)
		(property "Reference" "R214"
			(at 3.302 0.42037 90)
			(unlocked yes)
			(layer "F.SilkS")
			(effects
				(font
					(size 0.7874 0.5842)
					(thickness 0.1524)
				)
			)
		)
		(property "Value" "VAL*"
			(at 0.02032 2.13233 90)
			(unlocked yes)
			(layer "F.Fab")
			(hide yes)
			(effects
				(font
					(size 0.7874 0.5842)
					(thickness 0.1524)
				)
			)
		)
		(property "Device Type" "RESISTOR-G155-11001-01,1KOHM,1%"
			(at 0.008382 1.210564 90)
			(unlocked yes)
			(layer "F.Fab")
			(hide yes)
			(effects
				(font
					(size 0.7874 0.5842)
					(thickness 0.1524)
				)
			)
		)
		(property "User Part Number" "PARTNUM*"
			(at 0.02032 4.024884 90)
			(unlocked yes)
			(layer "Cmts.User")
			(hide yes)
			(effects
				(font
					(size 0.7874 0.5842)
					(thickness 0.1524)
				)
			)
		)
		(property "Tolerance" "TOL*"
			(at 0.044704 3.05435 90)
			(unlocked yes)
			(layer "Cmts.User")
			(hide yes)
			(effects
				(font
					(size 0.7874 0.5842)
					(thickness 0.1524)
				)
			)
		)
		(duplicate_pad_numbers_are_jumpers no)
		(fp_line
			(start 1.143 -0.5588)
			(end -1.143 -0.5588)
			(stroke
				(width 0.1)
				(type default)
			)
			(layer "F.SilkS")
		)
		(fp_line
			(start -1.143 -0.5588)
			(end -1.143 0.5588)
			(stroke
				(width 0.1)
				(type default)
			)
			(layer "F.SilkS")
		)
		(fp_line
			(start 1.143 0.5588)
			(end 1.143 -0.5588)
			(stroke
				(width 0.1)
				(type default)
			)
			(layer "F.SilkS")
		)
		(fp_line
			(start -1.143 0.5588)
			(end 1.143 0.5588)
			(stroke
				(width 0.1)
				(type default)
			)
			(layer "F.SilkS")
		)
		(fp_rect
			(start -1.143 0.5588)
			(end 1.143 -0.5588)
			(stroke
				(width 0)
				(type default)
			)
			(fill no)
			(layer "F.CrtYd")
		)
		(fp_line
			(start 0.508 -0.3048)
			(end -0.508 -0.3048)
			(stroke
				(width 0.1)
				(type default)
			)
			(layer "F.Fab")
		)
		(fp_line
			(start -0.508 -0.3048)
			(end -0.508 0.3048)
			(stroke
				(width 0.1)
				(type default)
			)
			(layer "F.Fab")
		)
		(fp_line
			(start 0.508 0.3048)
			(end 0.508 -0.3048)
			(stroke
				(width 0.1)
				(type default)
			)
			(layer "F.Fab")
		)
		(fp_line
			(start -0.508 0.3048)
			(end 0.508 0.3048)
			(stroke
				(width 0.1)
				(type default)
			)
			(layer "F.Fab")
		)
		(pad "1" smd rect
			(at -0.5334 0 90)
			(size 0.7112 0.6096)
			(layers "F.Cu" "F.Mask" "F.Paste")
			(net "FPGA_BRD_REV2")
		)
		(pad "2" smd rect
			(at 0.5334 0 90)
			(size 0.7112 0.6096)
			(layers "F.Cu" "F.Mask" "F.Paste")
			(net "SG")
		)
		(zone
			(layer "F.Cu")
			(hatch none 0.5)
			(connect_pads
				(clearance 0)
			)
			(min_thickness 0.25)
			(keepout
				(tracks allowed)
				(vias not_allowed)
				(pads allowed)
				(copperpour not_allowed)
				(footprints allowed)
			)
			(placement
				(enabled no)
				(sheetname "")
			)
			(fill
				(thermal_gap 0.5)
				(thermal_bridge_width 0.5)
				(island_removal_mode 0)
			)
			(polygon
				(pts
					(xy 113.0808 -61.8998) (xy 113.0808 -62.0522) (xy 112.4712 -62.0522) (xy 112.4712 -61.8998)
				)
			)
		)
	)
)
